(kicad_pcb
	(version 20260206)
	(generator "pcbnew")
	(generator_version "10.0")
	(general
		(thickness 1.6)
		(legacy_teardrops no)
	)
	(paper "A4")
	(title_block
		(title "Bryce Canyon_F.DPB_16315-1-OCP.brd")
		(comment 1 "Bryce Canyon / footprint 2183 of 2223 (IO2), pads 68-81 of 202")
	)
	(layers
		(0 "F.Cu" signal "TOP")
		(4 "In1.Cu" signal "L2GND")
		(6 "In2.Cu" signal "L3")
		(8 "In3.Cu" signal "L4GND")
		(10 "In4.Cu" signal "L5")
		(12 "In5.Cu" signal "L6VCC")
		(14 "In6.Cu" signal "L7VCC")
		(16 "In7.Cu" signal "L8")
		(18 "In8.Cu" signal "L9GND")
		(20 "In9.Cu" signal "L10")
		(22 "In10.Cu" signal "L11GND")
		(2 "B.Cu" signal "BOTTOM")
		(9 "F.Adhes" user "F.Adhesive")
		(11 "B.Adhes" user "B.Adhesive")
		(13 "F.Paste" user "Package Geometry/Pastemask Top")
		(15 "B.Paste" user "Package Geometry/Pastemask Bottom")
		(5 "F.SilkS" user "Ref Des/Silkscreen Top")
		(7 "B.SilkS" user "Ref Des/Silkscreen Bottom")
		(1 "F.Mask" user "Board Geometry/Soldermask Top")
		(3 "B.Mask" user "Board Geometry/Soldermask Bottom")
		(17 "Dwgs.User" user "User.Drawings")
		(19 "Cmts.User" user "User.Comments")
		(21 "Eco1.User" user "User.Eco1")
		(23 "Eco2.User" user "User.Eco2")
		(25 "Edge.Cuts" user "Board Geometry/Outline")
		(27 "Margin" user)
		(31 "F.CrtYd" user "Package Geometry/Place Bound Top")
		(29 "B.CrtYd" user "Package Geometry/Place Bound Bottom")
		(35 "F.Fab" user "Ref Des/Assembly Top")
		(33 "B.Fab" user "Ref Des/Assembly Bottom")
	)
	(footprint ""
		(layer "B.Cu")
		(at 389.349996 -30.550104 180)
		(property "Reference" "IO2"
			(at 0 0 0)
			(layer "B.SilkS")
			(hide yes)
			(effects
				(font
					(size 1.27 1.27)
				)
				(justify mirror)
			)
		)
		(property "Value" "DM-AMP-CONN200-13R-6-GP-01"
			(at 47.5488 -16.5862 180)
			(unlocked yes)
			(layer "B.Fab")
			(hide yes)
			(effects
				(font
					(size 1.016 1.016)
					(thickness 0.1524)
				)
				(justify mirror)
			)
		)
		(property "Device Type" "DMFIT-200P-384346H577-01"
			(at 47.5488 -18.1102 180)
			(unlocked yes)
			(layer "B.Fab")
			(hide yes)
			(effects
				(font
					(size 1.016 1.016)
					(thickness 0.1524)
				)
				(justify mirror)
			)
		)
		(duplicate_pad_numbers_are_jumpers no)
		(pad "E2" thru_hole circle
			(at 1.800098 -8.199882)
			(size 0.664718 0.664718)
			(drill 0.359918)
			(layers "*.Cu" "*.Mask")
			(remove_unused_layers no)
			(net "PCIE_IOM_B_TO_COMP_B_9_DN")
			(clearance 0.264414)
			(padstack
				(mode custom)
				(layer "In1.Cu"
					(shape circle)
					(size 0.664718 0.664718)
					(clearance 0.264414)
				)
				(layer "In2.Cu"
					(shape circle)
					(size 0.664718 0.664718)
					(clearance 0.264414)
				)
				(layer "In3.Cu"
					(shape circle)
					(size 0.664718 0.664718)
					(clearance 0.264414)
				)
				(layer "In4.Cu"
					(shape circle)
					(size 0.664718 0.664718)
					(clearance 0.264414)
				)
				(layer "In5.Cu"
					(shape circle)
					(size 0.664718 0.664718)
					(clearance 0.264414)
				)
				(layer "In6.Cu"
					(shape circle)
					(size 0.762 0.762)
					(clearance 0.1651)
				)
				(layer "In7.Cu"
					(shape circle)
					(size 0.762 0.762)
					(clearance 0.1651)
				)
				(layer "In8.Cu"
					(shape circle)
					(size 0.762 0.762)
					(clearance 0.1651)
				)
				(layer "In9.Cu"
					(shape circle)
					(size 0.762 0.762)
					(clearance 0.1651)
				)
				(layer "In10.Cu"
					(shape circle)
					(size 0.762 0.762)
					(clearance 0.1651)
				)
				(layer "B.Cu"
					(shape circle)
					(size 0.762 0.762)
					(thermal_gap 0.1651)
					(clearance 0.1651)
				)
			)
		)
		(pad "E3" thru_hole circle
			(at 3.599942 -7.199884)
			(size 0.664718 0.664718)
			(drill 0.359918)
			(layers "*.Cu" "*.Mask")
			(remove_unused_layers no)
			(net "PCIE_IOM_B_TO_COMP_B_10_DN")
			(clearance 0.264414)
			(padstack
				(mode custom)
				(layer "In1.Cu"
					(shape circle)
					(size 0.664718 0.664718)
					(clearance 0.264414)
				)
				(layer "In2.Cu"
					(shape circle)
					(size 0.664718 0.664718)
					(clearance 0.264414)
				)
				(layer "In3.Cu"
					(shape circle)
					(size 0.664718 0.664718)
					(clearance 0.264414)
				)
				(layer "In4.Cu"
					(shape circle)
					(size 0.664718 0.664718)
					(clearance 0.264414)
				)
				(layer "In5.Cu"
					(shape circle)
					(size 0.664718 0.664718)
					(clearance 0.264414)
				)
				(layer "In6.Cu"
					(shape circle)
					(size 0.762 0.762)
					(clearance 0.1651)
				)
				(layer "In7.Cu"
					(shape circle)
					(size 0.762 0.762)
					(clearance 0.1651)
				)
				(layer "In8.Cu"
					(shape circle)
					(size 0.762 0.762)
					(clearance 0.1651)
				)
				(layer "In9.Cu"
					(shape circle)
					(size 0.762 0.762)
					(clearance 0.1651)
				)
				(layer "In10.Cu"
					(shape circle)
					(size 0.762 0.762)
					(clearance 0.1651)
				)
				(layer "B.Cu"
					(shape circle)
					(size 0.762 0.762)
					(thermal_gap 0.1651)
					(clearance 0.1651)
				)
			)
		)
		(pad "E4" thru_hole circle
			(at 5.40004 -8.199882)
			(size 0.664718 0.664718)
			(drill 0.359918)
			(layers "*.Cu" "*.Mask")
			(remove_unused_layers no)
			(net "PCIE_IOM_B_TO_COMP_B_11_DN")
			(clearance 0.264414)
			(padstack
				(mode custom)
				(layer "In1.Cu"
					(shape circle)
					(size 0.664718 0.664718)
					(clearance 0.264414)
				)
				(layer "In2.Cu"
					(shape circle)
					(size 0.664718 0.664718)
					(clearance 0.264414)
				)
				(layer "In3.Cu"
					(shape circle)
					(size 0.664718 0.664718)
					(clearance 0.264414)
				)
				(layer "In4.Cu"
					(shape circle)
					(size 0.664718 0.664718)
					(clearance 0.264414)
				)
				(layer "In5.Cu"
					(shape circle)
					(size 0.664718 0.664718)
					(clearance 0.264414)
				)
				(layer "In6.Cu"
					(shape circle)
					(size 0.762 0.762)
					(clearance 0.1651)
				)
				(layer "In7.Cu"
					(shape circle)
					(size 0.762 0.762)
					(clearance 0.1651)
				)
				(layer "In8.Cu"
					(shape circle)
					(size 0.762 0.762)
					(clearance 0.1651)
				)
				(layer "In9.Cu"
					(shape circle)
					(size 0.762 0.762)
					(clearance 0.1651)
				)
				(layer "In10.Cu"
					(shape circle)
					(size 0.762 0.762)
					(clearance 0.1651)
				)
				(layer "B.Cu"
					(shape circle)
					(size 0.762 0.762)
					(thermal_gap 0.1651)
					(clearance 0.1651)
				)
			)
		)
		(pad "E5" thru_hole circle
			(at 7.199884 -7.199884)
			(size 0.664718 0.664718)
			(drill 0.359918)
			(layers "*.Cu" "*.Mask")
			(remove_unused_layers no)
			(net "PCIE_IOM_B_TO_COMP_B_12_DN")
			(clearance 0.264414)
			(padstack
				(mode custom)
				(layer "In1.Cu"
					(shape circle)
					(size 0.664718 0.664718)
					(clearance 0.264414)
				)
				(layer "In2.Cu"
					(shape circle)
					(size 0.664718 0.664718)
					(clearance 0.264414)
				)
				(layer "In3.Cu"
					(shape circle)
					(size 0.664718 0.664718)
					(clearance 0.264414)
				)
				(layer "In4.Cu"
					(shape circle)
					(size 0.664718 0.664718)
					(clearance 0.264414)
				)
				(layer "In5.Cu"
					(shape circle)
					(size 0.664718 0.664718)
					(clearance 0.264414)
				)
				(layer "In6.Cu"
					(shape circle)
					(size 0.762 0.762)
					(clearance 0.1651)
				)
				(layer "In7.Cu"
					(shape circle)
					(size 0.762 0.762)
					(clearance 0.1651)
				)
				(layer "In8.Cu"
					(shape circle)
					(size 0.762 0.762)
					(clearance 0.1651)
				)
				(layer "In9.Cu"
					(shape circle)
					(size 0.762 0.762)
					(clearance 0.1651)
				)
				(layer "In10.Cu"
					(shape circle)
					(size 0.762 0.762)
					(clearance 0.1651)
				)
				(layer "B.Cu"
					(shape circle)
					(size 0.762 0.762)
					(thermal_gap 0.1651)
					(clearance 0.1651)
				)
			)
		)
		(pad "E6" thru_hole circle
			(at 8.999982 -8.199882)
			(size 0.664718 0.664718)
			(drill 0.359918)
			(layers "*.Cu" "*.Mask")
			(remove_unused_layers no)
			(net "PCIE_IOM_B_TO_COMP_B_13_DN")
			(clearance 0.264414)
			(padstack
				(mode custom)
				(layer "In1.Cu"
					(shape circle)
					(size 0.664718 0.664718)
					(clearance 0.264414)
				)
				(layer "In2.Cu"
					(shape circle)
					(size 0.664718 0.664718)
					(clearance 0.264414)
				)
				(layer "In3.Cu"
					(shape circle)
					(size 0.664718 0.664718)
					(clearance 0.264414)
				)
				(layer "In4.Cu"
					(shape circle)
					(size 0.664718 0.664718)
					(clearance 0.264414)
				)
				(layer "In5.Cu"
					(shape circle)
					(size 0.664718 0.664718)
					(clearance 0.264414)
				)
				(layer "In6.Cu"
					(shape circle)
					(size 0.762 0.762)
					(clearance 0.1651)
				)
				(layer "In7.Cu"
					(shape circle)
					(size 0.762 0.762)
					(clearance 0.1651)
				)
				(layer "In8.Cu"
					(shape circle)
					(size 0.762 0.762)
					(clearance 0.1651)
				)
				(layer "In9.Cu"
					(shape circle)
					(size 0.762 0.762)
					(clearance 0.1651)
				)
				(layer "In10.Cu"
					(shape circle)
					(size 0.762 0.762)
					(clearance 0.1651)
				)
				(layer "B.Cu"
					(shape circle)
					(size 0.762 0.762)
					(thermal_gap 0.1651)
					(clearance 0.1651)
				)
			)
		)
		(pad "E7" thru_hole circle
			(at 10.80008 -7.199884)
			(size 0.664718 0.664718)
			(drill 0.359918)
			(layers "*.Cu" "*.Mask")
			(remove_unused_layers no)
			(net "PCIE_IOM_B_TO_COMP_B_14_DN")
			(clearance 0.264414)
			(padstack
				(mode custom)
				(layer "In1.Cu"
					(shape circle)
					(size 0.664718 0.664718)
					(clearance 0.264414)
				)
				(layer "In2.Cu"
					(shape circle)
					(size 0.664718 0.664718)
					(clearance 0.264414)
				)
				(layer "In3.Cu"
					(shape circle)
					(size 0.664718 0.664718)
					(clearance 0.264414)
				)
				(layer "In4.Cu"
					(shape circle)
					(size 0.664718 0.664718)
					(clearance 0.264414)
				)
				(layer "In5.Cu"
					(shape circle)
					(size 0.664718 0.664718)
					(clearance 0.264414)
				)
				(layer "In6.Cu"
					(shape circle)
					(size 0.762 0.762)
					(clearance 0.1651)
				)
				(layer "In7.Cu"
					(shape circle)
					(size 0.762 0.762)
					(clearance 0.1651)
				)
				(layer "In8.Cu"
					(shape circle)
					(size 0.762 0.762)
					(clearance 0.1651)
				)
				(layer "In9.Cu"
					(shape circle)
					(size 0.762 0.762)
					(clearance 0.1651)
				)
				(layer "In10.Cu"
					(shape circle)
					(size 0.762 0.762)
					(clearance 0.1651)
				)
				(layer "B.Cu"
					(shape circle)
					(size 0.762 0.762)
					(thermal_gap 0.1651)
					(clearance 0.1651)
				)
			)
		)
		(pad "E8" thru_hole circle
			(at 12.599924 -8.199882)
			(size 0.664718 0.664718)
			(drill 0.359918)
			(layers "*.Cu" "*.Mask")
			(remove_unused_layers no)
			(net "PCIE_IOM_B_TO_COMP_B_15_DN")
			(clearance 0.264414)
			(padstack
				(mode custom)
				(layer "In1.Cu"
					(shape circle)
					(size 0.664718 0.664718)
					(clearance 0.264414)
				)
				(layer "In2.Cu"
					(shape circle)
					(size 0.664718 0.664718)
					(clearance 0.264414)
				)
				(layer "In3.Cu"
					(shape circle)
					(size 0.664718 0.664718)
					(clearance 0.264414)
				)
				(layer "In4.Cu"
					(shape circle)
					(size 0.664718 0.664718)
					(clearance 0.264414)
				)
				(layer "In5.Cu"
					(shape circle)
					(size 0.664718 0.664718)
					(clearance 0.264414)
				)
				(layer "In6.Cu"
					(shape circle)
					(size 0.762 0.762)
					(clearance 0.1651)
				)
				(layer "In7.Cu"
					(shape circle)
					(size 0.762 0.762)
					(clearance 0.1651)
				)
				(layer "In8.Cu"
					(shape circle)
					(size 0.762 0.762)
					(clearance 0.1651)
				)
				(layer "In9.Cu"
					(shape circle)
					(size 0.762 0.762)
					(clearance 0.1651)
				)
				(layer "In10.Cu"
					(shape circle)
					(size 0.762 0.762)
					(clearance 0.1651)
				)
				(layer "B.Cu"
					(shape circle)
					(size 0.762 0.762)
					(thermal_gap 0.1651)
					(clearance 0.1651)
				)
			)
		)
		(pad "E9" thru_hole circle
			(at 21.599906 -7.199884)
			(size 0.664718 0.664718)
			(drill 0.359918)
			(layers "*.Cu" "*.Mask")
			(remove_unused_layers no)
			(net "PCIE_IOM_B_TO_COMP_B_23_DN")
			(clearance 0.264414)
			(padstack
				(mode custom)
				(layer "In1.Cu"
					(shape circle)
					(size 0.664718 0.664718)
					(clearance 0.264414)
				)
				(layer "In2.Cu"
					(shape circle)
					(size 0.664718 0.664718)
					(clearance 0.264414)
				)
				(layer "In3.Cu"
					(shape circle)
					(size 0.664718 0.664718)
					(clearance 0.264414)
				)
				(layer "In4.Cu"
					(shape circle)
					(size 0.664718 0.664718)
					(clearance 0.264414)
				)
				(layer "In5.Cu"
					(shape circle)
					(size 0.664718 0.664718)
					(clearance 0.264414)
				)
				(layer "In6.Cu"
					(shape circle)
					(size 0.762 0.762)
					(clearance 0.1651)
				)
				(layer "In7.Cu"
					(shape circle)
					(size 0.762 0.762)
					(clearance 0.1651)
				)
				(layer "In8.Cu"
					(shape circle)
					(size 0.762 0.762)
					(clearance 0.1651)
				)
				(layer "In9.Cu"
					(shape circle)
					(size 0.762 0.762)
					(clearance 0.1651)
				)
				(layer "In10.Cu"
					(shape circle)
					(size 0.762 0.762)
					(clearance 0.1651)
				)
				(layer "B.Cu"
					(shape circle)
					(size 0.762 0.762)
					(thermal_gap 0.1651)
					(clearance 0.1651)
				)
			)
		)
		(pad "E10" thru_hole circle
			(at 23.400004 -8.199882)
			(size 0.664718 0.664718)
			(drill 0.359918)
			(layers "*.Cu" "*.Mask")
			(remove_unused_layers no)
			(net "PCIE_IOM_B_TO_COMP_B_22_DN")
			(clearance 0.264414)
			(padstack
				(mode custom)
				(layer "In1.Cu"
					(shape circle)
					(size 0.664718 0.664718)
					(clearance 0.264414)
				)
				(layer "In2.Cu"
					(shape circle)
					(size 0.664718 0.664718)
					(clearance 0.264414)
				)
				(layer "In3.Cu"
					(shape circle)
					(size 0.664718 0.664718)
					(clearance 0.264414)
				)
				(layer "In4.Cu"
					(shape circle)
					(size 0.664718 0.664718)
					(clearance 0.264414)
				)
				(layer "In5.Cu"
					(shape circle)
					(size 0.664718 0.664718)
					(clearance 0.264414)
				)
				(layer "In6.Cu"
					(shape circle)
					(size 0.762 0.762)
					(clearance 0.1651)
				)
				(layer "In7.Cu"
					(shape circle)
					(size 0.762 0.762)
					(clearance 0.1651)
				)
				(layer "In8.Cu"
					(shape circle)
					(size 0.762 0.762)
					(clearance 0.1651)
				)
				(layer "In9.Cu"
					(shape circle)
					(size 0.762 0.762)
					(clearance 0.1651)
				)
				(layer "In10.Cu"
					(shape circle)
					(size 0.762 0.762)
					(clearance 0.1651)
				)
				(layer "B.Cu"
					(shape circle)
					(size 0.762 0.762)
					(thermal_gap 0.1651)
					(clearance 0.1651)
				)
			)
		)
		(pad "E11" thru_hole circle
			(at 25.200102 -7.199884)
			(size 0.664718 0.664718)
			(drill 0.359918)
			(layers "*.Cu" "*.Mask")
			(remove_unused_layers no)
			(net "PCIE_IOM_B_TO_COMP_B_21_DN")
			(clearance 0.264414)
			(padstack
				(mode custom)
				(layer "In1.Cu"
					(shape circle)
					(size 0.664718 0.664718)
					(clearance 0.264414)
				)
				(layer "In2.Cu"
					(shape circle)
					(size 0.664718 0.664718)
					(clearance 0.264414)
				)
				(layer "In3.Cu"
					(shape circle)
					(size 0.664718 0.664718)
					(clearance 0.264414)
				)
				(layer "In4.Cu"
					(shape circle)
					(size 0.664718 0.664718)
					(clearance 0.264414)
				)
				(layer "In5.Cu"
					(shape circle)
					(size 0.664718 0.664718)
					(clearance 0.264414)
				)
				(layer "In6.Cu"
					(shape circle)
					(size 0.762 0.762)
					(clearance 0.1651)
				)
				(layer "In7.Cu"
					(shape circle)
					(size 0.762 0.762)
					(clearance 0.1651)
				)
				(layer "In8.Cu"
					(shape circle)
					(size 0.762 0.762)
					(clearance 0.1651)
				)
				(layer "In9.Cu"
					(shape circle)
					(size 0.762 0.762)
					(clearance 0.1651)
				)
				(layer "In10.Cu"
					(shape circle)
					(size 0.762 0.762)
					(clearance 0.1651)
				)
				(layer "B.Cu"
					(shape circle)
					(size 0.762 0.762)
					(thermal_gap 0.1651)
					(clearance 0.1651)
				)
			)
		)
		(pad "E12" thru_hole circle
			(at 26.999946 -8.199882)
			(size 0.664718 0.664718)
			(drill 0.359918)
			(layers "*.Cu" "*.Mask")
			(remove_unused_layers no)
			(net "PCIE_IOM_B_TO_COMP_B_20_DN")
			(clearance 0.264414)
			(padstack
				(mode custom)
				(layer "In1.Cu"
					(shape circle)
					(size 0.664718 0.664718)
					(clearance 0.264414)
				)
				(layer "In2.Cu"
					(shape circle)
					(size 0.664718 0.664718)
					(clearance 0.264414)
				)
				(layer "In3.Cu"
					(shape circle)
					(size 0.664718 0.664718)
					(clearance 0.264414)
				)
				(layer "In4.Cu"
					(shape circle)
					(size 0.664718 0.664718)
					(clearance 0.264414)
				)
				(layer "In5.Cu"
					(shape circle)
					(size 0.664718 0.664718)
					(clearance 0.264414)
				)
				(layer "In6.Cu"
					(shape circle)
					(size 0.762 0.762)
					(clearance 0.1651)
				)
				(layer "In7.Cu"
					(shape circle)
					(size 0.762 0.762)
					(clearance 0.1651)
				)
				(layer "In8.Cu"
					(shape circle)
					(size 0.762 0.762)
					(clearance 0.1651)
				)
				(layer "In9.Cu"
					(shape circle)
					(size 0.762 0.762)
					(clearance 0.1651)
				)
				(layer "In10.Cu"
					(shape circle)
					(size 0.762 0.762)
					(clearance 0.1651)
				)
				(layer "B.Cu"
					(shape circle)
					(size 0.762 0.762)
					(thermal_gap 0.1651)
					(clearance 0.1651)
				)
			)
		)
		(pad "E13" thru_hole circle
			(at 28.800044 -7.199884)
			(size 0.664718 0.664718)
			(drill 0.359918)
			(layers "*.Cu" "*.Mask")
			(remove_unused_layers no)
			(net "PCIE_IOM_B_TO_COMP_B_19_DN")
			(clearance 0.264414)
			(padstack
				(mode custom)
				(layer "In1.Cu"
					(shape circle)
					(size 0.664718 0.664718)
					(clearance 0.264414)
				)
				(layer "In2.Cu"
					(shape circle)
					(size 0.664718 0.664718)
					(clearance 0.264414)
				)
				(layer "In3.Cu"
					(shape circle)
					(size 0.664718 0.664718)
					(clearance 0.264414)
				)
				(layer "In4.Cu"
					(shape circle)
					(size 0.664718 0.664718)
					(clearance 0.264414)
				)
				(layer "In5.Cu"
					(shape circle)
					(size 0.664718 0.664718)
					(clearance 0.264414)
				)
				(layer "In6.Cu"
					(shape circle)
					(size 0.762 0.762)
					(clearance 0.1651)
				)
				(layer "In7.Cu"
					(shape circle)
					(size 0.762 0.762)
					(clearance 0.1651)
				)
				(layer "In8.Cu"
					(shape circle)
					(size 0.762 0.762)
					(clearance 0.1651)
				)
				(layer "In9.Cu"
					(shape circle)
					(size 0.762 0.762)
					(clearance 0.1651)
				)
				(layer "In10.Cu"
					(shape circle)
					(size 0.762 0.762)
					(clearance 0.1651)
				)
				(layer "B.Cu"
					(shape circle)
					(size 0.762 0.762)
					(thermal_gap 0.1651)
					(clearance 0.1651)
				)
			)
		)
		(pad "E14" thru_hole circle
			(at 30.599888 -8.199882)
			(size 0.664718 0.664718)
			(drill 0.359918)
			(layers "*.Cu" "*.Mask")
			(remove_unused_layers no)
			(net "PCIE_IOM_B_TO_COMP_B_18_DN")
			(clearance 0.264414)
			(padstack
				(mode custom)
				(layer "In1.Cu"
					(shape circle)
					(size 0.664718 0.664718)
					(clearance 0.264414)
				)
				(layer "In2.Cu"
					(shape circle)
					(size 0.664718 0.664718)
					(clearance 0.264414)
				)
				(layer "In3.Cu"
					(shape circle)
					(size 0.664718 0.664718)
					(clearance 0.264414)
				)
				(layer "In4.Cu"
					(shape circle)
					(size 0.664718 0.664718)
					(clearance 0.264414)
				)
				(layer "In5.Cu"
					(shape circle)
					(size 0.664718 0.664718)
					(clearance 0.264414)
				)
				(layer "In6.Cu"
					(shape circle)
					(size 0.762 0.762)
					(clearance 0.1651)
				)
				(layer "In7.Cu"
					(shape circle)
					(size 0.762 0.762)
					(clearance 0.1651)
				)
				(layer "In8.Cu"
					(shape circle)
					(size 0.762 0.762)
					(clearance 0.1651)
				)
				(layer "In9.Cu"
					(shape circle)
					(size 0.762 0.762)
					(clearance 0.1651)
				)
				(layer "In10.Cu"
					(shape circle)
					(size 0.762 0.762)
					(clearance 0.1651)
				)
				(layer "B.Cu"
					(shape circle)
					(size 0.762 0.762)
					(thermal_gap 0.1651)
					(clearance 0.1651)
				)
			)
		)
		(pad "E15" thru_hole circle
			(at 32.399986 -7.199884)
			(size 0.664718 0.664718)
			(drill 0.359918)
			(layers "*.Cu" "*.Mask")
			(remove_unused_layers no)
			(net "PCIE_IOM_B_TO_COMP_B_17_DN")
			(clearance 0.264414)
			(padstack
				(mode custom)
				(layer "In1.Cu"
					(shape circle)
					(size 0.664718 0.664718)
					(clearance 0.264414)
				)
				(layer "In2.Cu"
					(shape circle)
					(size 0.664718 0.664718)
					(clearance 0.264414)
				)
				(layer "In3.Cu"
					(shape circle)
					(size 0.664718 0.664718)
					(clearance 0.264414)
				)
				(layer "In4.Cu"
					(shape circle)
					(size 0.664718 0.664718)
					(clearance 0.264414)
				)
				(layer "In5.Cu"
					(shape circle)
					(size 0.664718 0.664718)
					(clearance 0.264414)
				)
				(layer "In6.Cu"
					(shape circle)
					(size 0.762 0.762)
					(clearance 0.1651)
				)
				(layer "In7.Cu"
					(shape circle)
					(size 0.762 0.762)
					(clearance 0.1651)
				)
				(layer "In8.Cu"
					(shape circle)
					(size 0.762 0.762)
					(clearance 0.1651)
				)
				(layer "In9.Cu"
					(shape circle)
					(size 0.762 0.762)
					(clearance 0.1651)
				)
				(layer "In10.Cu"
					(shape circle)
					(size 0.762 0.762)
					(clearance 0.1651)
				)
				(layer "B.Cu"
					(shape circle)
					(size 0.762 0.762)
					(thermal_gap 0.1651)
					(clearance 0.1651)
				)
			)
		)
	)
)
